(kicad_pcb
	(version 20260206)
	(generator "pcbnew")
	(generator_version "10.0")
	(general
		(thickness 1.6)
		(legacy_teardrops no)
	)
	(paper "A4")
	(title_block
		(title "dpb — 14545-sa.0730WZS0815.brd")
		(comment 1 "Honey Badger (Wiwynn) / footprints 229-236 of 1066")
	)
	(layers
		(0 "F.Cu" signal "TOP")
		(4 "In1.Cu" signal "L2GND")
		(6 "In2.Cu" signal "L3")
		(8 "In3.Cu" signal "L4VCC")
		(10 "In4.Cu" signal "L5VCC")
		(12 "In5.Cu" signal "L6")
		(14 "In6.Cu" signal "L7GND")
		(2 "B.Cu" signal "BOTTOM")
		(9 "F.Adhes" user "F.Adhesive")
		(11 "B.Adhes" user "B.Adhesive")
		(13 "F.Paste" user "Package Geometry/Pastemask Top")
		(15 "B.Paste" user "Package Geometry/Pastemask Bottom")
		(5 "F.SilkS" user "Ref Des/Silkscreen Top")
		(7 "B.SilkS" user "Ref Des/Silkscreen Bottom")
		(1 "F.Mask" user "Board Geometry/Soldermask Top")
		(3 "B.Mask" user "Board Geometry/Soldermask Bottom")
		(17 "Dwgs.User" user "User.Drawings")
		(19 "Cmts.User" user "User.Comments")
		(21 "Eco1.User" user "User.Eco1")
		(23 "Eco2.User" user "User.Eco2")
		(25 "Edge.Cuts" user "Board Geometry/Outline")
		(27 "Margin" user)
		(31 "F.CrtYd" user "Package Geometry/Place Bound Top")
		(29 "B.CrtYd" user "Package Geometry/Place Bound Bottom")
		(35 "F.Fab" user "Ref Des/Assembly Top")
		(33 "B.Fab" user "Ref Des/Assembly Bottom")
	)
	(footprint ""
		(layer "F.Cu")
		(at 190.803784 -187.168028 180)
		(property "Reference" "R153"
			(at 0 0 180)
			(layer "F.SilkS")
			(hide yes)
			(effects
				(font
					(size 1.27 1.27)
				)
			)
		)
		(property "Value" "0R2J-2-GP"
			(at 0.064008 -3.993896 180)
			(unlocked yes)
			(layer "F.Fab")
			(hide yes)
			(effects
				(font
					(size 1.016 1.016)
					(thickness 0.1524)
				)
			)
		)
		(property "Device Type" "R402H16"
			(at 0.064008 -5.517896 180)
			(unlocked yes)
			(layer "F.Fab")
			(hide yes)
			(effects
				(font
					(size 1.016 1.016)
					(thickness 0.1524)
				)
			)
		)
		(duplicate_pad_numbers_are_jumpers no)
		(fp_line
			(start 0.508 -0.9398)
			(end -0.508 -0.9398)
			(stroke
				(width 0.1524)
				(type default)
			)
			(layer "F.SilkS")
		)
		(fp_line
			(start -0.508 -0.9398)
			(end -0.508 0.9398)
			(stroke
				(width 0.1524)
				(type default)
			)
			(layer "F.SilkS")
		)
		(fp_rect
			(start -0.508 0.9398)
			(end 0.508 -0.9398)
			(stroke
				(width 0)
				(type default)
			)
			(fill no)
			(layer "F.CrtYd")
		)
		(fp_rect
			(start -0.508 0.9398)
			(end 0.508 -0.9398)
			(stroke
				(width 0)
				(type default)
			)
			(fill no)
			(layer "F.Fab")
		)
		(pad "1" smd custom
			(at 0 -0.4445 180)
			(size 0.1397 0.1397)
			(layers "F.Cu" "F.Mask" "F.Paste")
			(net "SW_PWR_HDD3")
			(options
				(clearance outline)
				(anchor circle)
			)
			(primitives
				(gr_poly
					(pts
						(arc
							(start -0.1778 -0.2794)
							(mid -0.249642 -0.249642)
							(end -0.2794 -0.1778)
						)
						(arc
							(start -0.2794 0.1778)
							(mid -0.249642 0.249642)
							(end -0.1778 0.2794)
						)
						(arc
							(start 0.1778 0.2794)
							(mid 0.249642 0.249642)
							(end 0.2794 0.1778)
						)
						(arc
							(start 0.2794 -0.1778)
							(mid 0.249642 -0.249642)
							(end 0.1778 -0.2794)
						)
					)
					(width 0)
					(fill yes)
				)
			)
		)
		(pad "2" smd custom
			(at 0 0.4445 180)
			(size 0.1397 0.1397)
			(layers "F.Cu" "F.Mask" "F.Paste")
			(net "SW_PWR_R_HDD3")
			(options
				(clearance outline)
				(anchor circle)
			)
			(primitives
				(gr_poly
					(pts
						(arc
							(start -0.1778 -0.2794)
							(mid -0.249642 -0.249642)
							(end -0.2794 -0.1778)
						)
						(arc
							(start -0.2794 0.1778)
							(mid -0.249642 0.249642)
							(end -0.1778 0.2794)
						)
						(arc
							(start 0.1778 0.2794)
							(mid 0.249642 0.249642)
							(end 0.2794 0.1778)
						)
						(arc
							(start 0.2794 -0.1778)
							(mid 0.249642 -0.249642)
							(end 0.1778 -0.2794)
						)
					)
					(width 0)
					(fill yes)
				)
			)
		)
	)
	(footprint ""
		(layer "F.Cu")
		(at 212.851746 -454.1647 90)
		(property "Reference" "C342"
			(at 0 0 90)
			(layer "F.SilkS")
			(hide yes)
			(effects
				(font
					(size 1.27 1.27)
				)
			)
		)
		(property "Value" "SCD1U10V2KX-5GP"
			(at 1.1811 -2.7051 90)
			(unlocked yes)
			(layer "F.Fab")
			(hide yes)
			(effects
				(font
					(size 1.016 1.016)
					(thickness 0.1524)
				)
			)
		)
		(property "Device Type" "C402H22"
			(at 1.1811 -4.2291 90)
			(unlocked yes)
			(layer "F.Fab")
			(hide yes)
			(effects
				(font
					(size 1.016 1.016)
					(thickness 0.1524)
				)
			)
		)
		(duplicate_pad_numbers_are_jumpers no)
		(fp_rect
			(start -0.4318 0.9525)
			(end 0.4318 -0.9525)
			(stroke
				(width 0)
				(type default)
			)
			(fill no)
			(layer "F.CrtYd")
		)
		(fp_rect
			(start -0.4318 0.9525)
			(end 0.4318 -0.9525)
			(stroke
				(width 0)
				(type default)
			)
			(fill no)
			(layer "F.Fab")
		)
		(pad "1" smd custom
			(at 0 -0.4445 90)
			(size 0.1524 0.1524)
			(layers "F.Cu" "F.Mask" "F.Paste")
			(net "P3V3")
			(options
				(clearance outline)
				(anchor circle)
			)
			(primitives
				(gr_poly
					(pts
						(arc
							(start 0.3048 -0.2032)
							(mid 0.275042 -0.275042)
							(end 0.2032 -0.3048)
						)
						(arc
							(start -0.2032 -0.3048)
							(mid -0.275042 -0.275042)
							(end -0.3048 -0.2032)
						)
						(arc
							(start -0.3048 0.2032)
							(mid -0.275042 0.275042)
							(end -0.2032 0.3048)
						)
						(arc
							(start 0.2032 0.3048)
							(mid 0.275042 0.275042)
							(end 0.3048 0.2032)
						)
					)
					(width 0)
					(fill yes)
				)
			)
		)
		(pad "2" smd custom
			(at 0 0.4445 90)
			(size 0.1524 0.1524)
			(layers "F.Cu" "F.Mask" "F.Paste")
			(net "GND")
			(options
				(clearance outline)
				(anchor circle)
			)
			(primitives
				(gr_poly
					(pts
						(arc
							(start 0.3048 -0.2032)
							(mid 0.275042 -0.275042)
							(end 0.2032 -0.3048)
						)
						(arc
							(start -0.2032 -0.3048)
							(mid -0.275042 -0.275042)
							(end -0.3048 -0.2032)
						)
						(arc
							(start -0.3048 0.2032)
							(mid -0.275042 0.275042)
							(end -0.2032 0.3048)
						)
						(arc
							(start 0.2032 0.3048)
							(mid 0.275042 0.275042)
							(end 0.3048 0.2032)
						)
					)
					(width 0)
					(fill yes)
				)
			)
		)
	)
	(footprint ""
		(layer "F.Cu")
		(at 192.3796 -295.8592 90)
		(property "Reference" "D17"
			(at 0 0 90)
			(layer "F.SilkS")
			(hide yes)
			(effects
				(font
					(size 1.27 1.27)
				)
			)
		)
		(property "Value" "RB551V30-1-GP"
			(at 0 -6.7818 90)
			(unlocked yes)
			(layer "F.Fab")
			(hide yes)
			(effects
				(font
					(size 1.016 1.016)
					(thickness 0.1524)
				)
			)
		)
		(property "Device Type" "SOD323AKH44"
			(at 0 -8.6868 90)
			(unlocked yes)
			(layer "F.Fab")
			(hide yes)
			(effects
				(font
					(size 1.016 1.016)
					(thickness 0.1524)
				)
			)
		)
		(duplicate_pad_numbers_are_jumpers no)
		(fp_line
			(start 0.889 -1.9304)
			(end 0.889 2.159)
			(stroke
				(width 0.1524)
				(type default)
			)
			(layer "F.SilkS")
		)
		(fp_line
			(start -0.889 -1.9304)
			(end 0.889 -1.9304)
			(stroke
				(width 0.1524)
				(type default)
			)
			(layer "F.SilkS")
		)
		(fp_line
			(start 0.762 2.0574)
			(end -0.762 2.0574)
			(stroke
				(width 0.508)
				(type default)
			)
			(layer "F.SilkS")
		)
		(fp_line
			(start 0.889 2.159)
			(end -0.889 2.159)
			(stroke
				(width 0.1524)
				(type default)
			)
			(layer "F.SilkS")
		)
		(fp_line
			(start -0.889 2.159)
			(end -0.889 -1.9304)
			(stroke
				(width 0.1524)
				(type default)
			)
			(layer "F.SilkS")
		)
		(fp_rect
			(start -1.016 2.3114)
			(end 1.016 -2.0066)
			(stroke
				(width 0)
				(type default)
			)
			(fill no)
			(layer "F.CrtYd")
		)
		(fp_poly
			(pts
				(xy -1.016 -2.0066) (xy 1.016 -2.0066) (xy 1.016 2.3114) (xy -1.016 2.3114)
			)
			(stroke
				(width 0)
				(type default)
			)
			(fill no)
			(layer "F.Fab")
		)
		(pad "A" smd rect
			(at 0 -1.143 90)
			(size 0.5588 1.016)
			(layers "F.Cu" "F.Mask" "F.Paste")
			(net "SW_HDD2_R")
		)
		(pad "K" smd rect
			(at 0 1.143 90)
			(size 0.5588 1.016)
			(layers "F.Cu" "F.Mask" "F.Paste")
			(net "SW_HDD2_N")
		)
	)
	(footprint ""
		(layer "F.Cu")
		(at 36.957 -138.43 -90)
		(property "Reference" "R403"
			(at 0 0 270)
			(layer "F.SilkS")
			(hide yes)
			(effects
				(font
					(size 1.27 1.27)
				)
			)
		)
		(property "Value" "10KR2F-2-GP"
			(at 0.064008 -3.993896 270)
			(unlocked yes)
			(layer "F.Fab")
			(hide yes)
			(effects
				(font
					(size 1.016 1.016)
					(thickness 0.1524)
				)
			)
		)
		(property "Device Type" "R402H16"
			(at 0.064008 -5.517896 270)
			(unlocked yes)
			(layer "F.Fab")
			(hide yes)
			(effects
				(font
					(size 1.016 1.016)
					(thickness 0.1524)
				)
			)
		)
		(duplicate_pad_numbers_are_jumpers no)
		(fp_line
			(start -0.508 -0.9398)
			(end -0.508 0.9398)
			(stroke
				(width 0.1524)
				(type default)
			)
			(layer "F.SilkS")
		)
		(fp_line
			(start 0.508 -0.9398)
			(end -0.508 -0.9398)
			(stroke
				(width 0.1524)
				(type default)
			)
			(layer "F.SilkS")
		)
		(fp_rect
			(start -0.508 0.9398)
			(end 0.508 -0.9398)
			(stroke
				(width 0)
				(type default)
			)
			(fill no)
			(layer "F.CrtYd")
		)
		(fp_rect
			(start -0.508 0.9398)
			(end 0.508 -0.9398)
			(stroke
				(width 0)
				(type default)
			)
			(fill no)
			(layer "F.Fab")
		)
		(pad "1" smd custom
			(at 0 -0.4445 270)
			(size 0.1397 0.1397)
			(layers "F.Cu" "F.Mask" "F.Paste")
			(net "P12V")
			(options
				(clearance outline)
				(anchor circle)
			)
			(primitives
				(gr_poly
					(pts
						(arc
							(start -0.1778 -0.2794)
							(mid -0.249642 -0.249642)
							(end -0.2794 -0.1778)
						)
						(arc
							(start -0.2794 0.1778)
							(mid -0.249642 0.249642)
							(end -0.1778 0.2794)
						)
						(arc
							(start 0.1778 0.2794)
							(mid 0.249642 0.249642)
							(end 0.2794 0.1778)
						)
						(arc
							(start 0.2794 -0.1778)
							(mid 0.249642 -0.249642)
							(end 0.1778 -0.2794)
						)
					)
					(width 0)
					(fill yes)
				)
			)
		)
		(pad "2" smd custom
			(at 0 0.4445 270)
			(size 0.1397 0.1397)
			(layers "F.Cu" "F.Mask" "F.Paste")
			(net "HDD13_LED_G")
			(options
				(clearance outline)
				(anchor circle)
			)
			(primitives
				(gr_poly
					(pts
						(arc
							(start -0.1778 -0.2794)
							(mid -0.249642 -0.249642)
							(end -0.2794 -0.1778)
						)
						(arc
							(start -0.2794 0.1778)
							(mid -0.249642 0.249642)
							(end -0.1778 0.2794)
						)
						(arc
							(start 0.1778 0.2794)
							(mid 0.249642 0.249642)
							(end 0.2794 0.1778)
						)
						(arc
							(start 0.2794 -0.1778)
							(mid 0.249642 -0.249642)
							(end 0.1778 -0.2794)
						)
					)
					(width 0)
					(fill yes)
				)
			)
		)
	)
	(footprint ""
		(layer "F.Cu")
		(at 32.054546 -417.452302)
		(property "Reference" "C273"
			(at 0 0 0)
			(layer "F.SilkS")
			(hide yes)
			(effects
				(font
					(size 1.27 1.27)
				)
			)
		)
		(property "Value" "SC10U25V6KX-1GP"
			(at -0.0762 -5.1308 0)
			(unlocked yes)
			(layer "F.Fab")
			(hide yes)
			(effects
				(font
					(size 1.016 1.016)
					(thickness 0.1524)
				)
			)
		)
		(property "Device Type" "C1206H71"
			(at -0.127 -6.6548 0)
			(unlocked yes)
			(layer "F.Fab")
			(hide yes)
			(effects
				(font
					(size 1.016 1.016)
					(thickness 0.1524)
				)
			)
		)
		(duplicate_pad_numbers_are_jumpers no)
		(fp_line
			(start -1.016 -2.2352)
			(end 1.016 -2.2352)
			(stroke
				(width 0.1524)
				(type default)
			)
			(layer "F.SilkS")
		)
		(fp_line
			(start -1.016 -0.8382)
			(end -1.016 -2.2352)
			(stroke
				(width 0.1524)
				(type default)
			)
			(layer "F.SilkS")
		)
		(fp_line
			(start -1.016 2.2352)
			(end -1.016 0.8382)
			(stroke
				(width 0.1524)
				(type default)
			)
			(layer "F.SilkS")
		)
		(fp_line
			(start 1.016 -2.2352)
			(end 1.016 -0.8382)
			(stroke
				(width 0.1524)
				(type default)
			)
			(layer "F.SilkS")
		)
		(fp_line
			(start 1.016 0.8382)
			(end 1.016 2.2352)
			(stroke
				(width 0.1524)
				(type default)
			)
			(layer "F.SilkS")
		)
		(fp_line
			(start 1.016 2.2352)
			(end -1.016 2.2352)
			(stroke
				(width 0.1524)
				(type default)
			)
			(layer "F.SilkS")
		)
		(fp_rect
			(start -1.0922 2.3114)
			(end 1.0922 -2.3114)
			(stroke
				(width 0)
				(type default)
			)
			(fill no)
			(layer "F.CrtYd")
		)
		(fp_poly
			(pts
				(xy 1.0922 -2.3114) (xy 1.0922 2.3114) (xy -1.0922 2.3114) (xy -1.0922 -2.3114)
			)
			(stroke
				(width 0)
				(type default)
			)
			(fill no)
			(layer "F.Fab")
		)
		(pad "1" smd rect
			(at 0 -1.397)
			(size 1.651 1.27)
			(layers "F.Cu" "F.Mask" "F.Paste")
			(net "P12V_HDD10")
		)
		(pad "2" smd rect
			(at 0 1.397)
			(size 1.651 1.27)
			(layers "F.Cu" "F.Mask" "F.Paste")
			(net "GND")
		)
	)
	(footprint ""
		(layer "F.Cu")
		(at 20.066 -393.7)
		(property "Reference" "R508"
			(at 0 0 0)
			(layer "F.SilkS")
			(hide yes)
			(effects
				(font
					(size 1.27 1.27)
				)
			)
		)
		(property "Value" "0R2J-2-GP"
			(at 0.064008 -3.993896 0)
			(unlocked yes)
			(layer "F.Fab")
			(hide yes)
			(effects
				(font
					(size 1.016 1.016)
					(thickness 0.1524)
				)
			)
		)
		(property "Device Type" "R402H16"
			(at 0.064008 -5.517896 0)
			(unlocked yes)
			(layer "F.Fab")
			(hide yes)
			(effects
				(font
					(size 1.016 1.016)
					(thickness 0.1524)
				)
			)
		)
		(duplicate_pad_numbers_are_jumpers no)
		(fp_line
			(start -0.508 -0.9398)
			(end -0.508 0.9398)
			(stroke
				(width 0.1524)
				(type default)
			)
			(layer "F.SilkS")
		)
		(fp_line
			(start 0.508 -0.9398)
			(end -0.508 -0.9398)
			(stroke
				(width 0.1524)
				(type default)
			)
			(layer "F.SilkS")
		)
		(fp_rect
			(start -0.508 0.9398)
			(end 0.508 -0.9398)
			(stroke
				(width 0)
				(type default)
			)
			(fill no)
			(layer "F.CrtYd")
		)
		(fp_rect
			(start -0.508 0.9398)
			(end 0.508 -0.9398)
			(stroke
				(width 0)
				(type default)
			)
			(fill no)
			(layer "F.Fab")
		)
		(pad "1" smd custom
			(at 0 -0.4445)
			(size 0.1397 0.1397)
			(layers "F.Cu" "F.Mask" "F.Paste")
			(net "I2C_D_SCL_DAMP_A")
			(options
				(clearance outline)
				(anchor circle)
			)
			(primitives
				(gr_poly
					(pts
						(arc
							(start -0.1778 -0.2794)
							(mid -0.249642 -0.249642)
							(end -0.2794 -0.1778)
						)
						(arc
							(start -0.2794 0.1778)
							(mid -0.249642 0.249642)
							(end -0.1778 0.2794)
						)
						(arc
							(start 0.1778 0.2794)
							(mid 0.249642 0.249642)
							(end 0.2794 0.1778)
						)
						(arc
							(start 0.2794 -0.1778)
							(mid 0.249642 -0.249642)
							(end 0.1778 -0.2794)
						)
					)
					(width 0)
					(fill yes)
				)
			)
		)
		(pad "2" smd custom
			(at 0 0.4445)
			(size 0.1397 0.1397)
			(layers "F.Cu" "F.Mask" "F.Paste")
			(net "I2C_D_SCL")
			(options
				(clearance outline)
				(anchor circle)
			)
			(primitives
				(gr_poly
					(pts
						(arc
							(start -0.1778 -0.2794)
							(mid -0.249642 -0.249642)
							(end -0.2794 -0.1778)
						)
						(arc
							(start -0.2794 0.1778)
							(mid -0.249642 0.249642)
							(end -0.1778 0.2794)
						)
						(arc
							(start 0.1778 0.2794)
							(mid 0.249642 0.249642)
							(end 0.2794 0.1778)
						)
						(arc
							(start 0.2794 -0.1778)
							(mid 0.249642 -0.249642)
							(end 0.1778 -0.2794)
						)
					)
					(width 0)
					(fill yes)
				)
			)
		)
	)
	(footprint ""
		(layer "F.Cu")
		(at 193.167 -500.888 90)
		(property "Reference" "D15"
			(at 0 0 90)
			(layer "F.SilkS")
			(hide yes)
			(effects
				(font
					(size 1.27 1.27)
				)
			)
		)
		(property "Value" "RB551V30-1-GP"
			(at 0 -6.7818 90)
			(unlocked yes)
			(layer "F.Fab")
			(hide yes)
			(effects
				(font
					(size 1.016 1.016)
					(thickness 0.1524)
				)
			)
		)
		(property "Device Type" "SOD323AKH44"
			(at 0 -8.6868 90)
			(unlocked yes)
			(layer "F.Fab")
			(hide yes)
			(effects
				(font
					(size 1.016 1.016)
					(thickness 0.1524)
				)
			)
		)
		(duplicate_pad_numbers_are_jumpers no)
		(fp_line
			(start 0.889 -1.9304)
			(end 0.889 2.159)
			(stroke
				(width 0.1524)
				(type default)
			)
			(layer "F.SilkS")
		)
		(fp_line
			(start -0.889 -1.9304)
			(end 0.889 -1.9304)
			(stroke
				(width 0.1524)
				(type default)
			)
			(layer "F.SilkS")
		)
		(fp_line
			(start 0.762 2.0574)
			(end -0.762 2.0574)
			(stroke
				(width 0.508)
				(type default)
			)
			(layer "F.SilkS")
		)
		(fp_line
			(start 0.889 2.159)
			(end -0.889 2.159)
			(stroke
				(width 0.1524)
				(type default)
			)
			(layer "F.SilkS")
		)
		(fp_line
			(start -0.889 2.159)
			(end -0.889 -1.9304)
			(stroke
				(width 0.1524)
				(type default)
			)
			(layer "F.SilkS")
		)
		(fp_rect
			(start -1.016 2.3114)
			(end 1.016 -2.0066)
			(stroke
				(width 0)
				(type default)
			)
			(fill no)
			(layer "F.CrtYd")
		)
		(fp_poly
			(pts
				(xy -1.016 -2.0066) (xy 1.016 -2.0066) (xy 1.016 2.3114) (xy -1.016 2.3114)
			)
			(stroke
				(width 0)
				(type default)
			)
			(fill no)
			(layer "F.Fab")
		)
		(pad "A" smd rect
			(at 0 -1.143 90)
			(size 0.5588 1.016)
			(layers "F.Cu" "F.Mask" "F.Paste")
			(net "SW_HDD0_R")
		)
		(pad "K" smd rect
			(at 0 1.143 90)
			(size 0.5588 1.016)
			(layers "F.Cu" "F.Mask" "F.Paste")
			(net "SW_HDD0_N")
		)
	)
	(footprint ""
		(layer "F.Cu")
		(at 78.561946 -389.8773)
		(property "Reference" "C197"
			(at 0 0 0)
			(layer "F.SilkS")
			(hide yes)
			(effects
				(font
					(size 1.27 1.27)
				)
			)
		)
		(property "Value" "SCD1U10V2KX-5GP"
			(at 1.1811 -2.7051 0)
			(unlocked yes)
			(layer "F.Fab")
			(hide yes)
			(effects
				(font
					(size 1.016 1.016)
					(thickness 0.1524)
				)
			)
		)
		(property "Device Type" "C402H22"
			(at 1.1811 -4.2291 0)
			(unlocked yes)
			(layer "F.Fab")
			(hide yes)
			(effects
				(font
					(size 1.016 1.016)
					(thickness 0.1524)
				)
			)
		)
		(duplicate_pad_numbers_are_jumpers no)
		(fp_rect
			(start -0.4318 0.9525)
			(end 0.4318 -0.9525)
			(stroke
				(width 0)
				(type default)
			)
			(fill no)
			(layer "F.CrtYd")
		)
		(fp_rect
			(start -0.4318 0.9525)
			(end 0.4318 -0.9525)
			(stroke
				(width 0)
				(type default)
			)
			(fill no)
			(layer "F.Fab")
		)
		(pad "1" smd custom
			(at 0 -0.4445)
			(size 0.1524 0.1524)
			(layers "F.Cu" "F.Mask" "F.Paste")
			(net "P3V3")
			(options
				(clearance outline)
				(anchor circle)
			)
			(primitives
				(gr_poly
					(pts
						(arc
							(start 0.3048 -0.2032)
							(mid 0.275042 -0.275042)
							(end 0.2032 -0.3048)
						)
						(arc
							(start -0.2032 -0.3048)
							(mid -0.275042 -0.275042)
							(end -0.3048 -0.2032)
						)
						(arc
							(start -0.3048 0.2032)
							(mid -0.275042 0.275042)
							(end -0.2032 0.3048)
						)
						(arc
							(start 0.2032 0.3048)
							(mid 0.275042 0.275042)
							(end 0.3048 0.2032)
						)
					)
					(width 0)
					(fill yes)
				)
			)
		)
		(pad "2" smd custom
			(at 0 0.4445)
			(size 0.1524 0.1524)
			(layers "F.Cu" "F.Mask" "F.Paste")
			(net "GND")
			(options
				(clearance outline)
				(anchor circle)
			)
			(primitives
				(gr_poly
					(pts
						(arc
							(start 0.3048 -0.2032)
							(mid 0.275042 -0.275042)
							(end 0.2032 -0.3048)
						)
						(arc
							(start -0.2032 -0.3048)
							(mid -0.275042 -0.275042)
							(end -0.3048 -0.2032)
						)
						(arc
							(start -0.3048 0.2032)
							(mid -0.275042 0.275042)
							(end -0.2032 0.3048)
						)
						(arc
							(start 0.2032 0.3048)
							(mid 0.275042 0.275042)
							(end 0.3048 0.2032)
						)
					)
					(width 0)
					(fill yes)
				)
			)
		)
	)
)
